# S9S_MB_2U (Grand Teton) — schematic netlist excerpt (pin names and nets, part order shuffled) for the footprints in the layout excerpt that follows; sources: Cadence DE-HDL packaged netlist, KiCad conversion of 03242023_DA0F0TMBIJ0_F0T_Motherboard_J_brd_V01_OCP.brd

J37  SCONN168_ME1016810202011  IO  pkg CON_F168S2H7D_P0-6W2-95_LUH  page 153
  GND_A1  = GND
  GND_A2  = GND
  GND_A3  = GND
  GND_A4  = GND
  GND_A5  = GND
  GND_A6  = GND
  SMCLK  = SMB_OCP_SFF_3V3AUX_BUF_R_SCL
  SMDAT  = SMB_OCP_SFF_3V3AUX_BUF_R_SDA
  \smrst#\  = RST_SMB_OCP_SFF_N
  \prsnta#\  = OCP_SFF_PRSNTA_R_N
  \perst1#\  = RST_PERST1_OCP_SFF_N
  \prsntb2#\  = OCP_SFF_PRSNT2_R_N
  GND_A13  = GND
  REFCLKN1  = CLK_100M_OCP_SFF_1_DN
  REFCLKP1  = CLK_100M_OCP_SFF_1_DP
  GND_A16  = GND
  PERN0  = P5E_CPU0_PE1_RX_DN<0>
  PERP0  = P5E_CPU0_PE1_RX_DP<0>
  GND_A19  = GND
  PERN1  = P5E_CPU0_PE1_RX_DP<1>
  PERP1  = P5E_CPU0_PE1_RX_DN<1>
  GND_A22  = GND
  PERN2  = P5E_CPU0_PE1_RX_DP<2>
  PERP2  = P5E_CPU0_PE1_RX_DN<2>
  GND_A25  = GND
  PERN3  = P5E_CPU0_PE1_RX_DP<3>
  PERP3  = P5E_CPU0_PE1_RX_DN<3>
  GND_A28  = GND
  GND_A29  = GND
  PERN4  = P5E_CPU0_PE1_RX_DP<4>
  PERP4  = P5E_CPU0_PE1_RX_DN<4>
  GND_A32  = GND
  PERN5  = P5E_CPU0_PE1_RX_DP<5>
  PERP5  = P5E_CPU0_PE1_RX_DN<5>
  GND_A35  = GND
  PERN6  = P5E_CPU0_PE1_RX_DP<6>
  PERP6  = P5E_CPU0_PE1_RX_DN<6>
  GND_A38  = GND
  PERN7  = P5E_CPU0_PE1_RX_DP<7>
  PERP7  = P5E_CPU0_PE1_RX_DN<7>
  GND_A41  = GND
  \prsntb1#\  = OCP_SFF_PRSNT1_R_N
  GND_A43  = GND
  PERN8  = P5E_CPU0_PE1_RX_DP<8>
  PERP8  = P5E_CPU0_PE1_RX_DN<8>
  GND_A46  = GND
  PERN9  = P5E_CPU0_PE1_RX_DP<9>
  PERP9  = P5E_CPU0_PE1_RX_DN<9>
  GND_A49  = GND
  PERN10  = P5E_CPU0_PE1_RX_DP<10>
  PERP10  = P5E_CPU0_PE1_RX_DN<10>
  GND_A52  = GND
  PERN11  = P5E_CPU0_PE1_RX_DP<11>
  PERP11  = P5E_CPU0_PE1_RX_DN<11>
  GND_A55  = GND
  PERN12  = P5E_CPU0_PE1_RX_DP<12>
  PERP12  = P5E_CPU0_PE1_RX_DN<12>
  GND_A58  = GND
  PERN13  = P5E_CPU0_PE1_RX_DP<13>
  PERP13  = P5E_CPU0_PE1_RX_DN<13>
  GND_A61  = GND
  PERN14  = P5E_CPU0_PE1_RX_DP<14>
  PERP14  = P5E_CPU0_PE1_RX_DN<14>
  GND_A64  = GND
  PERN15  = P5E_CPU0_PE1_RX_DP<15>
  PERP15  = P5E_CPU0_PE1_RX_DN<15>
  GND_A67  = GND
  USB_DATN  = OCP_SFF_USB2_3_DN
  USB_DATP  = OCP_SFF_USB2_3_DP
  \pwrbrk0#\  = OCP_SFF_PWRBRK_N
  \+12v_edge_b1\  = P12V_OCP_SFF
  \+12v_edge_b2\  = P12V_OCP_SFF
  \+12v_edge_b3\  = P12V_OCP_SFF
  \+12v_edge_b4\  = P12V_OCP_SFF
  \+12v_edge_b5\  = P12V_OCP_SFF
  \+12v_edge_b6\  = P12V_OCP_SFF
  \bif0#\  = OCP_SFF_BIF0_R_N
  \bif1#\  = OCP_SFF_BIF1_R_N
  \bif2#\  = OCP_SFF_BIF2_R_N
  \perst0#\  = RST_PERST0_OCP_SFF_N
  \+3.3v_edge\  = P3V3_OCP_SFF
  AUX_PWR_EN  = OCP_SFF_AUX_PWR_EN_R
  GND_B13  = GND
  REFCLKN0  = CLK_100M_OCP_SFF_0_DN
  REFCLKP0  = CLK_100M_OCP_SFF_0_DP
  GND_B16  = GND
  PETN0  = P5E_CPU0_PE1_TX_C_DN<0>
  PETP0  = P5E_CPU0_PE1_TX_C_DP<0>
  GND_B19  = GND
  PETN1  = P5E_CPU0_PE1_TX_C_DN<1>
  PETP1  = P5E_CPU0_PE1_TX_C_DP<1>
  GND_B22  = GND
  PETN2  = P5E_CPU0_PE1_TX_C_DP<2>
  PETP2  = P5E_CPU0_PE1_TX_C_DN<2>
  GND_B25  = GND
  PETN3  = P5E_CPU0_PE1_TX_C_DN<3>
  PETP3  = P5E_CPU0_PE1_TX_C_DP<3>
  GND_B28  = GND
  GND_B29  = GND
  PETN4  = P5E_CPU0_PE1_TX_C_DP<4>
  PETP4  = P5E_CPU0_PE1_TX_C_DN<4>
  GND_B32  = GND
  PETN5  = P5E_CPU0_PE1_TX_C_DN<5>
  PETP5  = P5E_CPU0_PE1_TX_C_DP<5>
  GND_B35  = GND
  PETN6  = P5E_CPU0_PE1_TX_C_DP<6>
  PETP6  = P5E_CPU0_PE1_TX_C_DN<6>
  GND_B38  = GND
  PETN7  = P5E_CPU0_PE1_TX_C_DN<7>
  PETP7  = P5E_CPU0_PE1_TX_C_DP<7>
  GND_B41  = GND
  \prsntb0#\  = OCP_SFF_PRSNT0_R_N
  GND_B43  = GND
  PETN8  = P5E_CPU0_PE1_TX_C_DP<8>
  PETP8  = P5E_CPU0_PE1_TX_C_DN<8>
  GND_B46  = GND
  PETN9  = P5E_CPU0_PE1_TX_C_DN<9>
  PETP9  = P5E_CPU0_PE1_TX_C_DP<9>
  GND_B49  = GND
  PETN10  = P5E_CPU0_PE1_TX_C_DP<10>
  PETP10  = P5E_CPU0_PE1_TX_C_DN<10>
  GND_B52  = GND
  PETN11  = P5E_CPU0_PE1_TX_C_DN<11>
  PETP11  = P5E_CPU0_PE1_TX_C_DP<11>
  GND_B55  = GND
  PETN12  = P5E_CPU0_PE1_TX_C_DP<12>
  PETP12  = P5E_CPU0_PE1_TX_C_DN<12>
  GND_B58  = GND
  PETN13  = P5E_CPU0_PE1_TX_C_DN<13>
  PETP13  = P5E_CPU0_PE1_TX_C_DP<13>
  GND_B61  = GND
  PETN14  = P5E_CPU0_PE1_TX_C_DP<14>
  PETP14  = P5E_CPU0_PE1_TX_C_DN<14>
  GND_B64  = GND
  PETN15  = P5E_CPU0_PE1_TX_C_DN<15>
  PETP15  = P5E_CPU0_PE1_TX_C_DP<15>
  GND_B67  = GND
  RFU1_NC_B68  = TP_OCP_SFF_B68
  RFU1_NC_B69  = TP_OCP_SFF_B69
  \prsntb3#\  = OCP_SFF_PRSNT3_R_N
  G1  = GND
  G2  = GND
  G3  = GND
  G4  = GND
  G5  = GND
  \perst2#\  = RST_PERST2_OCP_SFF_N
  \perst3#\  = RST_PERST3_OCP_SFF_N
  \wake#\  = IRQ_LVC3_OCP_SFF_WAKE_N
  RBT_ARB_IN  = OCP_SFF_ISO1_RBT_ARB_IN
  RBT_ARB_OUT  = OCP_SFF_ISO2_RBT_ARB_OUT
  SLOT_ID1  = OCP_SFF_ID1
  RBT_TX_EN  = NCSI_OCP_SFF_TX_EN
  RBT_TXD1  = NCSI_OCP_SFF_TXD1
  RBT_TXD0  = NCSI_OCP_SFF_TXD0
  GND_OA10  = GND
  REFCLKN3  = CLK_100M_OCP_SFF_3_DN
  REFCLKP3  = CLK_100M_OCP_SFF_3_DP
  GND_OA13  = GND
  RBT_CLK_IN  = CLK_50M_NCSI_OCP_SFF_ISO
  NIC_PWR_GOOD  = FM_OCP_SFF_PWR_GOOD
  MAIN_PWR_EN  = OCP_SFF_MAIN_PWR_EN_R
  \ld#\  = SGPIO_OCP_SFF_LD_N
  DATA_IN  = SGPIO_OCP_SFF_DATAIN
  DATA_OUT  = SGPIO_OCP_SFF_DATAOUT
  CLK  = SGPIO_OCP_SFF_CLK
  SLOT_ID0  = OCP_SFF_ID0
  RBT_RXD1  = NCSI_OCP_SFF_RXD1
  RBT_RXD0  = NCSI_OCP_SFF_RXD0
  GND_OB10  = GND
  REFCLKN2  = CLK_100M_OCP_SFF_2_DN
  REFCLKP2  = CLK_100M_OCP_SFF_2_DP
  GND_OB13  = GND
  RBT_CRS_DV  = NCSI_OCP_SFF_CRS_DV

(kicad_pcb
	(version 20260206)
	(generator "pcbnew")
	(generator_version "10.0")
	(general
		(thickness 1.6)
		(legacy_teardrops no)
	)
	(paper "A4")
	(title_block
		(title "03242023_DA0F0TMBIJ0_F0T_Motherboard_J_brd_V01_OCP.brd")
		(comment 1 "Grand Teton / footprint 2414 of 6105 (J37), pads 90-133 of 175")
	)
	(layers
		(0 "F.Cu" signal "TOP")
		(4 "In1.Cu" signal "GND")
		(6 "In2.Cu" signal "IN1")
		(8 "In3.Cu" signal "GND1")
		(10 "In4.Cu" signal "IN2")
		(12 "In5.Cu" signal "GND2")
		(14 "In6.Cu" signal "IN3")
		(16 "In7.Cu" signal "GND3")
		(18 "In8.Cu" signal "VCC")
		(20 "In9.Cu" signal "VCC1")
		(22 "In10.Cu" signal "GND4")
		(24 "In11.Cu" signal "IN4")
		(26 "In12.Cu" signal "GND5")
		(28 "In13.Cu" signal "IN5")
		(30 "In14.Cu" signal "GND6")
		(32 "In15.Cu" signal "IN6")
		(34 "In16.Cu" signal "GND7")
		(2 "B.Cu" signal "BOTTOM")
		(9 "F.Adhes" user "F.Adhesive")
		(11 "B.Adhes" user "B.Adhesive")
		(13 "F.Paste" user "Package Geometry/Pastemask Top")
		(15 "B.Paste" user "Package Geometry/Pastemask Bottom")
		(5 "F.SilkS" user "Ref Des/Silkscreen Top")
		(7 "B.SilkS" user "Ref Des/Silkscreen Bottom")
		(1 "F.Mask" user "Board Geometry/Soldermask Top")
		(3 "B.Mask" user "Board Geometry/Soldermask Bottom")
		(17 "Dwgs.User" user "User.Drawings")
		(19 "Cmts.User" user "User.Comments")
		(21 "Eco1.User" user "User.Eco1")
		(23 "Eco2.User" user "User.Eco2")
		(25 "Edge.Cuts" user "Board Geometry/Outline")
		(27 "Margin" user)
		(31 "F.CrtYd" user "Package Geometry/Place Bound Top")
		(29 "B.CrtYd" user "Package Geometry/Place Bound Bottom")
		(35 "F.Fab" user "Ref Des/Assembly Top")
		(33 "B.Fab" user "Ref Des/Assembly Bottom")
	)
	(footprint ""
		(layer "F.Cu")
		(at 421.901874 -5.569966 -90)
		(property "Reference" "J37"
			(at -16.985996 31.63951 0)
			(unlocked yes)
			(layer "F.SilkS")
			(effects
				(font
					(size 0.7874 0.5842)
					(thickness 0.1524)
				)
				(justify left)
			)
		)
		(property "Value" ""
			(at 0 0 270)
			(layer "F.Fab")
			(effects
				(font
					(size 1.27 1.27)
				)
			)
		)
		(duplicate_pad_numbers_are_jumpers no)
		(pad "B18" smd rect
			(at -5.700014 -8.264906 180)
			(size 0.381 1.4478)
			(layers "F.Cu" "F.Mask" "F.Paste")
			(net "P5E_CPU0_PE1_TX_C_DP<0>")
		)
		(pad "B19" smd rect
			(at -5.700014 -7.664958 180)
			(size 0.381 1.4478)
			(layers "F.Cu" "F.Mask" "F.Paste")
			(net "GND")
		)
		(pad "B20" smd rect
			(at -5.700014 -7.06501 180)
			(size 0.381 1.4478)
			(layers "F.Cu" "F.Mask" "F.Paste")
			(net "P5E_CPU0_PE1_TX_C_DN<1>")
		)
		(pad "B21" smd rect
			(at -5.700014 -6.465062 180)
			(size 0.381 1.4478)
			(layers "F.Cu" "F.Mask" "F.Paste")
			(net "P5E_CPU0_PE1_TX_C_DP<1>")
		)
		(pad "B22" smd rect
			(at -5.700014 -5.865114 180)
			(size 0.381 1.4478)
			(layers "F.Cu" "F.Mask" "F.Paste")
			(net "GND")
		)
		(pad "B23" smd rect
			(at -5.700014 -5.264912 180)
			(size 0.381 1.4478)
			(layers "F.Cu" "F.Mask" "F.Paste")
			(net "P5E_CPU0_PE1_TX_C_DP<2>")
		)
		(pad "B24" smd rect
			(at -5.700014 -4.664964 180)
			(size 0.381 1.4478)
			(layers "F.Cu" "F.Mask" "F.Paste")
			(net "P5E_CPU0_PE1_TX_C_DN<2>")
		)
		(pad "B25" smd rect
			(at -5.700014 -4.065016 180)
			(size 0.381 1.4478)
			(layers "F.Cu" "F.Mask" "F.Paste")
			(net "GND")
		)
		(pad "B26" smd rect
			(at -5.700014 -3.465068 180)
			(size 0.381 1.4478)
			(layers "F.Cu" "F.Mask" "F.Paste")
			(net "P5E_CPU0_PE1_TX_C_DN<3>")
		)
		(pad "B27" smd rect
			(at -5.700014 -2.86512 180)
			(size 0.381 1.4478)
			(layers "F.Cu" "F.Mask" "F.Paste")
			(net "P5E_CPU0_PE1_TX_C_DP<3>")
		)
		(pad "B28" smd rect
			(at -5.700014 -2.264918 180)
			(size 0.381 1.4478)
			(layers "F.Cu" "F.Mask" "F.Paste")
			(net "GND")
		)
		(pad "B29" smd rect
			(at -5.700014 1.74498 180)
			(size 0.381 1.4478)
			(layers "F.Cu" "F.Mask" "F.Paste")
			(net "GND")
		)
		(pad "B30" smd rect
			(at -5.700014 2.344928 180)
			(size 0.381 1.4478)
			(layers "F.Cu" "F.Mask" "F.Paste")
			(net "P5E_CPU0_PE1_TX_C_DP<4>")
		)
		(pad "B31" smd rect
			(at -5.700014 2.944876 180)
			(size 0.381 1.4478)
			(layers "F.Cu" "F.Mask" "F.Paste")
			(net "P5E_CPU0_PE1_TX_C_DN<4>")
		)
		(pad "B32" smd rect
			(at -5.700014 3.545078 180)
			(size 0.381 1.4478)
			(layers "F.Cu" "F.Mask" "F.Paste")
			(net "GND")
		)
		(pad "B33" smd rect
			(at -5.700014 4.145026 180)
			(size 0.381 1.4478)
			(layers "F.Cu" "F.Mask" "F.Paste")
			(net "P5E_CPU0_PE1_TX_C_DN<5>")
		)
		(pad "B34" smd rect
			(at -5.700014 4.744974 180)
			(size 0.381 1.4478)
			(layers "F.Cu" "F.Mask" "F.Paste")
			(net "P5E_CPU0_PE1_TX_C_DP<5>")
		)
		(pad "B35" smd rect
			(at -5.700014 5.344922 180)
			(size 0.381 1.4478)
			(layers "F.Cu" "F.Mask" "F.Paste")
			(net "GND")
		)
		(pad "B36" smd rect
			(at -5.700014 5.945124 180)
			(size 0.381 1.4478)
			(layers "F.Cu" "F.Mask" "F.Paste")
			(net "P5E_CPU0_PE1_TX_C_DP<6>")
		)
		(pad "B37" smd rect
			(at -5.700014 6.545072 180)
			(size 0.381 1.4478)
			(layers "F.Cu" "F.Mask" "F.Paste")
			(net "P5E_CPU0_PE1_TX_C_DN<6>")
		)
		(pad "B38" smd rect
			(at -5.700014 7.14502 180)
			(size 0.381 1.4478)
			(layers "F.Cu" "F.Mask" "F.Paste")
			(net "GND")
		)
		(pad "B39" smd rect
			(at -5.700014 7.744968 180)
			(size 0.381 1.4478)
			(layers "F.Cu" "F.Mask" "F.Paste")
			(net "P5E_CPU0_PE1_TX_C_DN<7>")
		)
		(pad "B40" smd rect
			(at -5.700014 8.344916 180)
			(size 0.381 1.4478)
			(layers "F.Cu" "F.Mask" "F.Paste")
			(net "P5E_CPU0_PE1_TX_C_DP<7>")
		)
		(pad "B41" smd rect
			(at -5.700014 8.945118 180)
			(size 0.381 1.4478)
			(layers "F.Cu" "F.Mask" "F.Paste")
			(net "GND")
		)
		(pad "B42" smd rect
			(at -5.700014 9.545066 180)
			(size 0.381 1.4478)
			(layers "F.Cu" "F.Mask" "F.Paste")
			(net "OCP_SFF_PRSNT0_R_N")
		)
		(pad "B43" smd rect
			(at -5.700014 14.454886 180)
			(size 0.381 1.4478)
			(layers "F.Cu" "F.Mask" "F.Paste")
			(net "GND")
		)
		(pad "B44" smd rect
			(at -5.700014 15.055088 180)
			(size 0.381 1.4478)
			(layers "F.Cu" "F.Mask" "F.Paste")
			(net "P5E_CPU0_PE1_TX_C_DP<8>")
		)
		(pad "B45" smd rect
			(at -5.700014 15.655036 180)
			(size 0.381 1.4478)
			(layers "F.Cu" "F.Mask" "F.Paste")
			(net "P5E_CPU0_PE1_TX_C_DN<8>")
		)
		(pad "B46" smd rect
			(at -5.700014 16.254984 180)
			(size 0.381 1.4478)
			(layers "F.Cu" "F.Mask" "F.Paste")
			(net "GND")
		)
		(pad "B47" smd rect
			(at -5.700014 16.854932 180)
			(size 0.381 1.4478)
			(layers "F.Cu" "F.Mask" "F.Paste")
			(net "P5E_CPU0_PE1_TX_C_DN<9>")
		)
		(pad "B48" smd rect
			(at -5.700014 17.45488 180)
			(size 0.381 1.4478)
			(layers "F.Cu" "F.Mask" "F.Paste")
			(net "P5E_CPU0_PE1_TX_C_DP<9>")
		)
		(pad "B49" smd rect
			(at -5.700014 18.055082 180)
			(size 0.381 1.4478)
			(layers "F.Cu" "F.Mask" "F.Paste")
			(net "GND")
		)
		(pad "B50" smd rect
			(at -5.700014 18.65503 180)
			(size 0.381 1.4478)
			(layers "F.Cu" "F.Mask" "F.Paste")
			(net "P5E_CPU0_PE1_TX_C_DP<10>")
		)
		(pad "B51" smd rect
			(at -5.700014 19.254978 180)
			(size 0.381 1.4478)
			(layers "F.Cu" "F.Mask" "F.Paste")
			(net "P5E_CPU0_PE1_TX_C_DN<10>")
		)
		(pad "B52" smd rect
			(at -5.700014 19.854926 180)
			(size 0.381 1.4478)
			(layers "F.Cu" "F.Mask" "F.Paste")
			(net "GND")
		)
		(pad "B53" smd rect
			(at -5.700014 20.455128 180)
			(size 0.381 1.4478)
			(layers "F.Cu" "F.Mask" "F.Paste")
			(net "P5E_CPU0_PE1_TX_C_DN<11>")
		)
		(pad "B54" smd rect
			(at -5.700014 21.055076 180)
			(size 0.381 1.4478)
			(layers "F.Cu" "F.Mask" "F.Paste")
			(net "P5E_CPU0_PE1_TX_C_DP<11>")
		)
		(pad "B55" smd rect
			(at -5.700014 21.655024 180)
			(size 0.381 1.4478)
			(layers "F.Cu" "F.Mask" "F.Paste")
			(net "GND")
		)
		(pad "B56" smd rect
			(at -5.700014 22.254972 180)
			(size 0.381 1.4478)
			(layers "F.Cu" "F.Mask" "F.Paste")
			(net "P5E_CPU0_PE1_TX_C_DP<12>")
		)
		(pad "B57" smd rect
			(at -5.700014 22.85492 180)
			(size 0.381 1.4478)
			(layers "F.Cu" "F.Mask" "F.Paste")
			(net "P5E_CPU0_PE1_TX_C_DN<12>")
		)
		(pad "B58" smd rect
			(at -5.700014 23.455122 180)
			(size 0.381 1.4478)
			(layers "F.Cu" "F.Mask" "F.Paste")
			(net "GND")
		)
		(pad "B59" smd rect
			(at -5.700014 24.05507 180)
			(size 0.381 1.4478)
			(layers "F.Cu" "F.Mask" "F.Paste")
			(net "P5E_CPU0_PE1_TX_C_DN<13>")
		)
		(pad "B60" smd rect
			(at -5.700014 24.655018 180)
			(size 0.381 1.4478)
			(layers "F.Cu" "F.Mask" "F.Paste")
			(net "P5E_CPU0_PE1_TX_C_DP<13>")
		)
		(pad "B61" smd rect
			(at -5.700014 25.254966 180)
			(size 0.381 1.4478)
			(layers "F.Cu" "F.Mask" "F.Paste")
			(net "GND")
		)
	)
)
